(kicad_pcb
	(version 20260206)
	(generator "pcbnew")
	(generator_version "10.0")
	(general
		(thickness 1.6)
		(legacy_teardrops no)
	)
	(paper "A4")
	(title_block
		(title "panther-plus-userver — 13130-1b_20150205.brd")
		(comment 1 "Honey Badger (Wiwynn) / footprint 406 of 1509 (DIMM2), pads 121-127 of 210")
	)
	(layers
		(0 "F.Cu" signal "TOP")
		(4 "In1.Cu" signal "L2")
		(6 "In2.Cu" signal "L3")
		(8 "In3.Cu" signal "L4")
		(10 "In4.Cu" signal "L5")
		(12 "In5.Cu" signal "L6")
		(14 "In6.Cu" signal "L7")
		(16 "In7.Cu" signal "L8")
		(18 "In8.Cu" signal "L9")
		(20 "In9.Cu" signal "L10")
		(22 "In10.Cu" signal "L11")
		(2 "B.Cu" signal "BOTTOM")
		(9 "F.Adhes" user "F.Adhesive")
		(11 "B.Adhes" user "B.Adhesive")
		(13 "F.Paste" user "Package Geometry/Pastemask Top")
		(15 "B.Paste" user "Package Geometry/Pastemask Bottom")
		(5 "F.SilkS" user "Ref Des/Silkscreen Top")
		(7 "B.SilkS" user "Ref Des/Silkscreen Bottom")
		(1 "F.Mask" user "Board Geometry/Soldermask Top")
		(3 "B.Mask" user "Board Geometry/Soldermask Bottom")
		(17 "Dwgs.User" user "User.Drawings")
		(19 "Cmts.User" user "User.Comments")
		(21 "Eco1.User" user "User.Eco1")
		(23 "Eco2.User" user "User.Eco2")
		(25 "Edge.Cuts" user "Board Geometry/Outline")
		(27 "Margin" user)
		(31 "F.CrtYd" user "Package Geometry/Place Bound Top")
		(29 "B.CrtYd" user "Package Geometry/Place Bound Bottom")
		(35 "F.Fab" user "Ref Des/Assembly Top")
		(33 "B.Fab" user "Ref Des/Assembly Bottom")
	)
	(footprint ""
		(layer "F.Cu")
		(at 158.500064 -66.699892 180)
		(property "Reference" "DIMM2"
			(at 0 0 180)
			(layer "F.SilkS")
			(hide yes)
			(effects
				(font
					(size 1.27 1.27)
				)
			)
		)
		(property "Value" "DDR3-204P-174-COLAY-1-GP"
			(at -40.682164 -17.468088 180)
			(unlocked yes)
			(layer "F.Fab")
			(hide yes)
			(effects
				(font
					(size 1.016 1.016)
					(thickness 0.1524)
				)
			)
		)
		(property "Device Type" "AS0A626-H8SN-7H-COLAY-1"
			(at -40.682164 -18.992088 180)
			(unlocked yes)
			(layer "F.Fab")
			(hide yes)
			(effects
				(font
					(size 1.016 1.016)
					(thickness 0.1524)
				)
			)
		)
		(duplicate_pad_numbers_are_jumpers no)
		(pad "119" smd custom
			(at 6.150102 4.106672 180)
			(size 0.1143 0.1143)
			(layers "F.Cu" "F.Mask" "F.Paste")
			(net "M_A_BS0")
			(options
				(clearance outline)
				(anchor circle)
			)
			(primitives
				(gr_poly
					(pts
						(xy 0 0.9017) (xy -0.03175 0.89916) (xy -0.0635 0.889) (xy -0.09144 0.87376) (xy -0.11684 0.85344)
						(xy -0.13716 0.82804) (xy -0.1524 0.8001) (xy -0.16256 0.76835) (xy -0.1651 0.7366) (xy -0.1651 0.11938)
						(xy -0.17272 0.11176) (xy -0.19812 0.0762) (xy -0.2032 0.06604) (xy -0.20701 0.05715) (xy -0.21209 0.04699)
						(xy -0.2159 0.03683) (xy -0.21844 0.02667) (xy -0.22225 0.01524) (xy -0.22352 0.00508) (xy -0.22606 -0.00508)
						(xy -0.22733 -0.01651) (xy -0.22733 -0.02667) (xy -0.2286 -0.0381) (xy -0.22733 -0.04953) (xy -0.22733 -0.05969)
						(xy -0.22606 -0.07112) (xy -0.22352 -0.08128) (xy -0.22225 -0.09144) (xy -0.21844 -0.10287) (xy -0.2159 -0.11303)
						(xy -0.21209 -0.12319) (xy -0.20701 -0.13335) (xy -0.2032 -0.14224) (xy -0.19812 -0.1524) (xy -0.17272 -0.18796)
						(xy -0.1651 -0.19558) (xy -0.1651 -0.7366) (xy -0.16256 -0.76835) (xy -0.1524 -0.8001) (xy -0.13716 -0.82804)
						(xy -0.11684 -0.85344) (xy -0.09144 -0.87376) (xy -0.0635 -0.889) (xy -0.03175 -0.89916) (xy 0 -0.9017)
						(xy 0.03175 -0.89916) (xy 0.0635 -0.889) (xy 0.09144 -0.87376) (xy 0.11684 -0.85344) (xy 0.13716 -0.82804)
						(xy 0.1524 -0.8001) (xy 0.16256 -0.76835) (xy 0.1651 -0.7366) (xy 0.1651 -0.19685) (xy 0.17272 -0.18923)
						(xy 0.17907 -0.18034) (xy 0.18669 -0.17145) (xy 0.19177 -0.16256) (xy 0.19812 -0.15367) (xy 0.20828 -0.13335)
						(xy 0.21971 -0.10287) (xy 0.22225 -0.09271) (xy 0.22479 -0.08128) (xy 0.22606 -0.07112) (xy 0.2286 -0.05969)
						(xy 0.2286 -0.01651) (xy 0.22606 -0.00508) (xy 0.22479 0.00508) (xy 0.22225 0.01651) (xy 0.21971 0.02667)
						(xy 0.20828 0.05715) (xy 0.19812 0.07747) (xy 0.19177 0.08636) (xy 0.18669 0.09525) (xy 0.17907 0.10414)
						(xy 0.17272 0.11303) (xy 0.1651 0.12065) (xy 0.1651 0.7366) (xy 0.16256 0.76835) (xy 0.1524 0.8001)
						(xy 0.13716 0.82804) (xy 0.11684 0.85344) (xy 0.09144 0.87376) (xy 0.0635 0.889) (xy 0.03175 0.89916)
					)
					(width 0)
					(fill yes)
				)
			)
		)
		(pad "120" smd custom
			(at 6.450076 -4.106672 180)
			(size 0.1143 0.1143)
			(layers "F.Cu" "F.Mask" "F.Paste")
			(net "Net_11")
			(options
				(clearance outline)
				(anchor circle)
			)
			(primitives
				(gr_poly
					(pts
						(xy 0 0.9017) (xy -0.03175 0.89916) (xy -0.0635 0.889) (xy -0.09144 0.87376) (xy -0.11684 0.85344)
						(xy -0.13716 0.82804) (xy -0.1524 0.8001) (xy -0.16256 0.76835) (xy -0.1651 0.7366) (xy -0.1651 0.19685)
						(xy -0.17272 0.18923) (xy -0.17907 0.18034) (xy -0.18669 0.17145) (xy -0.19177 0.16256) (xy -0.19812 0.15367)
						(xy -0.20828 0.13335) (xy -0.21971 0.10287) (xy -0.22225 0.09271) (xy -0.22479 0.08128) (xy -0.22606 0.07112)
						(xy -0.2286 0.05969) (xy -0.2286 0.01651) (xy -0.22606 0.00508) (xy -0.22479 -0.00508) (xy -0.22225 -0.01651)
						(xy -0.21971 -0.02667) (xy -0.20828 -0.05715) (xy -0.19812 -0.07747) (xy -0.19177 -0.08636) (xy -0.18669 -0.09525)
						(xy -0.17907 -0.10414) (xy -0.17272 -0.11303) (xy -0.1651 -0.12065) (xy -0.1651 -0.7366) (xy -0.16256 -0.76835)
						(xy -0.1524 -0.8001) (xy -0.13716 -0.82804) (xy -0.11684 -0.85344) (xy -0.09144 -0.87376) (xy -0.0635 -0.889)
						(xy -0.03175 -0.89916) (xy 0 -0.9017) (xy 0.03175 -0.89916) (xy 0.0635 -0.889) (xy 0.09144 -0.87376)
						(xy 0.11684 -0.85344) (xy 0.13716 -0.82804) (xy 0.1524 -0.8001) (xy 0.16256 -0.76835) (xy 0.1651 -0.7366)
						(xy 0.1651 -0.11938) (xy 0.17272 -0.11176) (xy 0.19812 -0.0762) (xy 0.2032 -0.06604) (xy 0.20701 -0.05715)
						(xy 0.21209 -0.04699) (xy 0.2159 -0.03683) (xy 0.21844 -0.02667) (xy 0.22225 -0.01524) (xy 0.22352 -0.00508)
						(xy 0.22606 0.00508) (xy 0.22733 0.01651) (xy 0.22733 0.02667) (xy 0.2286 0.0381) (xy 0.22733 0.04953)
						(xy 0.22733 0.05969) (xy 0.22606 0.07112) (xy 0.22352 0.08128) (xy 0.22225 0.09144) (xy 0.21844 0.10287)
						(xy 0.2159 0.11303) (xy 0.21209 0.12319) (xy 0.20701 0.13335) (xy 0.2032 0.14224) (xy 0.19812 0.1524)
						(xy 0.17272 0.18796) (xy 0.1651 0.19558) (xy 0.1651 0.7366) (xy 0.16256 0.76835) (xy 0.1524 0.8001)
						(xy 0.13716 0.82804) (xy 0.11684 0.85344) (xy 0.09144 0.87376) (xy 0.0635 0.889) (xy 0.03175 0.89916)
					)
					(width 0)
					(fill yes)
				)
			)
		)
		(pad "121" smd custom
			(at 6.75005 4.106672 180)
			(size 0.1143 0.1143)
			(layers "F.Cu" "F.Mask" "F.Paste")
			(net "M_A_WE#")
			(options
				(clearance outline)
				(anchor circle)
			)
			(primitives
				(gr_poly
					(pts
						(xy 0 0.9017) (xy -0.03175 0.89916) (xy -0.0635 0.889) (xy -0.09144 0.87376) (xy -0.11684 0.85344)
						(xy -0.13716 0.82804) (xy -0.1524 0.8001) (xy -0.16256 0.76835) (xy -0.1651 0.7366) (xy -0.1651 -0.13462)
						(xy -0.17272 -0.14224) (xy -0.19812 -0.1778) (xy -0.2032 -0.18796) (xy -0.20701 -0.19685) (xy -0.21209 -0.20701)
						(xy -0.2159 -0.21717) (xy -0.21844 -0.22733) (xy -0.22225 -0.23876) (xy -0.22352 -0.24892) (xy -0.22606 -0.25908)
						(xy -0.22733 -0.27051) (xy -0.22733 -0.28067) (xy -0.2286 -0.2921) (xy -0.22733 -0.30353) (xy -0.22733 -0.31369)
						(xy -0.22606 -0.32512) (xy -0.22352 -0.33528) (xy -0.22225 -0.34544) (xy -0.21844 -0.35687) (xy -0.2159 -0.36703)
						(xy -0.21209 -0.37719) (xy -0.20701 -0.38735) (xy -0.2032 -0.39624) (xy -0.19812 -0.4064) (xy -0.17272 -0.44196)
						(xy -0.1651 -0.44958) (xy -0.1651 -0.7366) (xy -0.16256 -0.76835) (xy -0.1524 -0.8001) (xy -0.13716 -0.82804)
						(xy -0.11684 -0.85344) (xy -0.09144 -0.87376) (xy -0.0635 -0.889) (xy -0.03175 -0.89916) (xy 0 -0.9017)
						(xy 0.03175 -0.89916) (xy 0.0635 -0.889) (xy 0.09144 -0.87376) (xy 0.11684 -0.85344) (xy 0.13716 -0.82804)
						(xy 0.1524 -0.8001) (xy 0.16256 -0.76835) (xy 0.1651 -0.7366) (xy 0.1651 -0.44958) (xy 0.17272 -0.44196)
						(xy 0.19812 -0.4064) (xy 0.2032 -0.39624) (xy 0.20701 -0.38735) (xy 0.21209 -0.37719) (xy 0.2159 -0.36703)
						(xy 0.21844 -0.35687) (xy 0.22225 -0.34544) (xy 0.22352 -0.33528) (xy 0.22606 -0.32512) (xy 0.22733 -0.31369)
						(xy 0.22733 -0.30353) (xy 0.2286 -0.2921) (xy 0.22733 -0.28067) (xy 0.22733 -0.27051) (xy 0.22606 -0.25908)
						(xy 0.22352 -0.24892) (xy 0.22225 -0.23876) (xy 0.21844 -0.22733) (xy 0.2159 -0.21717) (xy 0.21209 -0.20701)
						(xy 0.20701 -0.19685) (xy 0.2032 -0.18796) (xy 0.19812 -0.1778) (xy 0.17272 -0.14224) (xy 0.1651 -0.13462)
						(xy 0.1651 0.7366) (xy 0.16256 0.76835) (xy 0.1524 0.8001) (xy 0.13716 0.82804) (xy 0.11684 0.85344)
						(xy 0.09144 0.87376) (xy 0.0635 0.889) (xy 0.03175 0.89916)
					)
					(width 0)
					(fill yes)
				)
			)
		)
		(pad "122" smd custom
			(at 7.050024 -4.106672 180)
			(size 0.1143 0.1143)
			(layers "F.Cu" "F.Mask" "F.Paste")
			(net "M_A_RAS#")
			(options
				(clearance outline)
				(anchor circle)
			)
			(primitives
				(gr_poly
					(pts
						(xy 0 0.9017) (xy -0.03175 0.89916) (xy -0.0635 0.889) (xy -0.09144 0.87376) (xy -0.11684 0.85344)
						(xy -0.13716 0.82804) (xy -0.1524 0.8001) (xy -0.16256 0.76835) (xy -0.1651 0.7366) (xy -0.1651 0.44958)
						(xy -0.17272 0.44196) (xy -0.19812 0.4064) (xy -0.2032 0.39624) (xy -0.20701 0.38735) (xy -0.21209 0.37719)
						(xy -0.2159 0.36703) (xy -0.21844 0.35687) (xy -0.22225 0.34544) (xy -0.22352 0.33528) (xy -0.22606 0.32512)
						(xy -0.22733 0.31369) (xy -0.22733 0.30353) (xy -0.2286 0.2921) (xy -0.22733 0.28067) (xy -0.22733 0.27051)
						(xy -0.22606 0.25908) (xy -0.22352 0.24892) (xy -0.22225 0.23876) (xy -0.21844 0.22733) (xy -0.2159 0.21717)
						(xy -0.21209 0.20701) (xy -0.20701 0.19685) (xy -0.2032 0.18796) (xy -0.19812 0.1778) (xy -0.17272 0.14224)
						(xy -0.1651 0.13462) (xy -0.1651 -0.7366) (xy -0.16256 -0.76835) (xy -0.1524 -0.8001) (xy -0.13716 -0.82804)
						(xy -0.11684 -0.85344) (xy -0.09144 -0.87376) (xy -0.0635 -0.889) (xy -0.03175 -0.89916) (xy 0 -0.9017)
						(xy 0.03175 -0.89916) (xy 0.0635 -0.889) (xy 0.09144 -0.87376) (xy 0.11684 -0.85344) (xy 0.13716 -0.82804)
						(xy 0.1524 -0.8001) (xy 0.16256 -0.76835) (xy 0.1651 -0.7366) (xy 0.1651 0.13462) (xy 0.17272 0.14224)
						(xy 0.19812 0.1778) (xy 0.2032 0.18796) (xy 0.20701 0.19685) (xy 0.21209 0.20701) (xy 0.2159 0.21717)
						(xy 0.21844 0.22733) (xy 0.22225 0.23876) (xy 0.22352 0.24892) (xy 0.22606 0.25908) (xy 0.22733 0.27051)
						(xy 0.22733 0.28067) (xy 0.2286 0.2921) (xy 0.22733 0.30353) (xy 0.22733 0.31369) (xy 0.22606 0.32512)
						(xy 0.22352 0.33528) (xy 0.22225 0.34544) (xy 0.21844 0.35687) (xy 0.2159 0.36703) (xy 0.21209 0.37719)
						(xy 0.20701 0.38735) (xy 0.2032 0.39624) (xy 0.19812 0.4064) (xy 0.17272 0.44196) (xy 0.1651 0.44958)
						(xy 0.1651 0.7366) (xy 0.16256 0.76835) (xy 0.1524 0.8001) (xy 0.13716 0.82804) (xy 0.11684 0.85344)
						(xy 0.09144 0.87376) (xy 0.0635 0.889) (xy 0.03175 0.89916)
					)
					(width 0)
					(fill yes)
				)
			)
		)
		(pad "123" smd custom
			(at 7.349998 4.106672 180)
			(size 0.1143 0.1143)
			(layers "F.Cu" "F.Mask" "F.Paste")
			(net "PV_VDDR")
			(options
				(clearance outline)
				(anchor circle)
			)
			(primitives
				(gr_poly
					(pts
						(xy 0 0.9017) (xy -0.03175 0.89916) (xy -0.0635 0.889) (xy -0.09144 0.87376) (xy -0.11684 0.85344)
						(xy -0.13716 0.82804) (xy -0.1524 0.8001) (xy -0.16256 0.76835) (xy -0.1651 0.7366) (xy -0.1651 0.11938)
						(xy -0.17272 0.11176) (xy -0.19812 0.0762) (xy -0.2032 0.06604) (xy -0.20701 0.05715) (xy -0.21209 0.04699)
						(xy -0.2159 0.03683) (xy -0.21844 0.02667) (xy -0.22225 0.01524) (xy -0.22352 0.00508) (xy -0.22606 -0.00508)
						(xy -0.22733 -0.01651) (xy -0.22733 -0.02667) (xy -0.2286 -0.0381) (xy -0.22733 -0.04953) (xy -0.22733 -0.05969)
						(xy -0.22606 -0.07112) (xy -0.22352 -0.08128) (xy -0.22225 -0.09144) (xy -0.21844 -0.10287) (xy -0.2159 -0.11303)
						(xy -0.21209 -0.12319) (xy -0.20701 -0.13335) (xy -0.2032 -0.14224) (xy -0.19812 -0.1524) (xy -0.17272 -0.18796)
						(xy -0.1651 -0.19558) (xy -0.1651 -0.7366) (xy -0.16256 -0.76835) (xy -0.1524 -0.8001) (xy -0.13716 -0.82804)
						(xy -0.11684 -0.85344) (xy -0.09144 -0.87376) (xy -0.0635 -0.889) (xy -0.03175 -0.89916) (xy 0 -0.9017)
						(xy 0.03175 -0.89916) (xy 0.0635 -0.889) (xy 0.09144 -0.87376) (xy 0.11684 -0.85344) (xy 0.13716 -0.82804)
						(xy 0.1524 -0.8001) (xy 0.16256 -0.76835) (xy 0.1651 -0.7366) (xy 0.1651 -0.19685) (xy 0.17272 -0.18923)
						(xy 0.17907 -0.18034) (xy 0.18669 -0.17145) (xy 0.19177 -0.16256) (xy 0.19812 -0.15367) (xy 0.20828 -0.13335)
						(xy 0.21971 -0.10287) (xy 0.22225 -0.09271) (xy 0.22479 -0.08128) (xy 0.22606 -0.07112) (xy 0.2286 -0.05969)
						(xy 0.2286 -0.01651) (xy 0.22606 -0.00508) (xy 0.22479 0.00508) (xy 0.22225 0.01651) (xy 0.21971 0.02667)
						(xy 0.20828 0.05715) (xy 0.19812 0.07747) (xy 0.19177 0.08636) (xy 0.18669 0.09525) (xy 0.17907 0.10414)
						(xy 0.17272 0.11303) (xy 0.1651 0.12065) (xy 0.1651 0.7366) (xy 0.16256 0.76835) (xy 0.1524 0.8001)
						(xy 0.13716 0.82804) (xy 0.11684 0.85344) (xy 0.09144 0.87376) (xy 0.0635 0.889) (xy 0.03175 0.89916)
					)
					(width 0)
					(fill yes)
				)
			)
		)
		(pad "124" smd custom
			(at 7.649972 -4.106672 180)
			(size 0.1143 0.1143)
			(layers "F.Cu" "F.Mask" "F.Paste")
			(net "PV_VDDR")
			(options
				(clearance outline)
				(anchor circle)
			)
			(primitives
				(gr_poly
					(pts
						(xy 0 0.9017) (xy -0.03175 0.89916) (xy -0.0635 0.889) (xy -0.09144 0.87376) (xy -0.11684 0.85344)
						(xy -0.13716 0.82804) (xy -0.1524 0.8001) (xy -0.16256 0.76835) (xy -0.1651 0.7366) (xy -0.1651 0.19685)
						(xy -0.17272 0.18923) (xy -0.17907 0.18034) (xy -0.18669 0.17145) (xy -0.19177 0.16256) (xy -0.19812 0.15367)
						(xy -0.20828 0.13335) (xy -0.21971 0.10287) (xy -0.22225 0.09271) (xy -0.22479 0.08128) (xy -0.22606 0.07112)
						(xy -0.2286 0.05969) (xy -0.2286 0.01651) (xy -0.22606 0.00508) (xy -0.22479 -0.00508) (xy -0.22225 -0.01651)
						(xy -0.21971 -0.02667) (xy -0.20828 -0.05715) (xy -0.19812 -0.07747) (xy -0.19177 -0.08636) (xy -0.18669 -0.09525)
						(xy -0.17907 -0.10414) (xy -0.17272 -0.11303) (xy -0.1651 -0.12065) (xy -0.1651 -0.7366) (xy -0.16256 -0.76835)
						(xy -0.1524 -0.8001) (xy -0.13716 -0.82804) (xy -0.11684 -0.85344) (xy -0.09144 -0.87376) (xy -0.0635 -0.889)
						(xy -0.03175 -0.89916) (xy 0 -0.9017) (xy 0.03175 -0.89916) (xy 0.0635 -0.889) (xy 0.09144 -0.87376)
						(xy 0.11684 -0.85344) (xy 0.13716 -0.82804) (xy 0.1524 -0.8001) (xy 0.16256 -0.76835) (xy 0.1651 -0.7366)
						(xy 0.1651 -0.11938) (xy 0.17272 -0.11176) (xy 0.19812 -0.0762) (xy 0.2032 -0.06604) (xy 0.20701 -0.05715)
						(xy 0.21209 -0.04699) (xy 0.2159 -0.03683) (xy 0.21844 -0.02667) (xy 0.22225 -0.01524) (xy 0.22352 -0.00508)
						(xy 0.22606 0.00508) (xy 0.22733 0.01651) (xy 0.22733 0.02667) (xy 0.2286 0.0381) (xy 0.22733 0.04953)
						(xy 0.22733 0.05969) (xy 0.22606 0.07112) (xy 0.22352 0.08128) (xy 0.22225 0.09144) (xy 0.21844 0.10287)
						(xy 0.2159 0.11303) (xy 0.21209 0.12319) (xy 0.20701 0.13335) (xy 0.2032 0.14224) (xy 0.19812 0.1524)
						(xy 0.17272 0.18796) (xy 0.1651 0.19558) (xy 0.1651 0.7366) (xy 0.16256 0.76835) (xy 0.1524 0.8001)
						(xy 0.13716 0.82804) (xy 0.11684 0.85344) (xy 0.09144 0.87376) (xy 0.0635 0.889) (xy 0.03175 0.89916)
					)
					(width 0)
					(fill yes)
				)
			)
		)
		(pad "125" smd custom
			(at 7.949946 4.106672 180)
			(size 0.1143 0.1143)
			(layers "F.Cu" "F.Mask" "F.Paste")
			(net "M_A_CAS#")
			(options
				(clearance outline)
				(anchor circle)
			)
			(primitives
				(gr_poly
					(pts
						(xy 0 0.9017) (xy -0.03175 0.89916) (xy -0.0635 0.889) (xy -0.09144 0.87376) (xy -0.11684 0.85344)
						(xy -0.13716 0.82804) (xy -0.1524 0.8001) (xy -0.16256 0.76835) (xy -0.1651 0.7366) (xy -0.1651 -0.13462)
						(xy -0.17272 -0.14224) (xy -0.19812 -0.1778) (xy -0.2032 -0.18796) (xy -0.20701 -0.19685) (xy -0.21209 -0.20701)
						(xy -0.2159 -0.21717) (xy -0.21844 -0.22733) (xy -0.22225 -0.23876) (xy -0.22352 -0.24892) (xy -0.22606 -0.25908)
						(xy -0.22733 -0.27051) (xy -0.22733 -0.28067) (xy -0.2286 -0.2921) (xy -0.22733 -0.30353) (xy -0.22733 -0.31369)
						(xy -0.22606 -0.32512) (xy -0.22352 -0.33528) (xy -0.22225 -0.34544) (xy -0.21844 -0.35687) (xy -0.2159 -0.36703)
						(xy -0.21209 -0.37719) (xy -0.20701 -0.38735) (xy -0.2032 -0.39624) (xy -0.19812 -0.4064) (xy -0.17272 -0.44196)
						(xy -0.1651 -0.44958) (xy -0.1651 -0.7366) (xy -0.16256 -0.76835) (xy -0.1524 -0.8001) (xy -0.13716 -0.82804)
						(xy -0.11684 -0.85344) (xy -0.09144 -0.87376) (xy -0.0635 -0.889) (xy -0.03175 -0.89916) (xy 0 -0.9017)
						(xy 0.03175 -0.89916) (xy 0.0635 -0.889) (xy 0.09144 -0.87376) (xy 0.11684 -0.85344) (xy 0.13716 -0.82804)
						(xy 0.1524 -0.8001) (xy 0.16256 -0.76835) (xy 0.1651 -0.7366) (xy 0.1651 -0.44958) (xy 0.17272 -0.44196)
						(xy 0.19812 -0.4064) (xy 0.2032 -0.39624) (xy 0.20701 -0.38735) (xy 0.21209 -0.37719) (xy 0.2159 -0.36703)
						(xy 0.21844 -0.35687) (xy 0.22225 -0.34544) (xy 0.22352 -0.33528) (xy 0.22606 -0.32512) (xy 0.22733 -0.31369)
						(xy 0.22733 -0.30353) (xy 0.2286 -0.2921) (xy 0.22733 -0.28067) (xy 0.22733 -0.27051) (xy 0.22606 -0.25908)
						(xy 0.22352 -0.24892) (xy 0.22225 -0.23876) (xy 0.21844 -0.22733) (xy 0.2159 -0.21717) (xy 0.21209 -0.20701)
						(xy 0.20701 -0.19685) (xy 0.2032 -0.18796) (xy 0.19812 -0.1778) (xy 0.17272 -0.14224) (xy 0.1651 -0.13462)
						(xy 0.1651 0.7366) (xy 0.16256 0.76835) (xy 0.1524 0.8001) (xy 0.13716 0.82804) (xy 0.11684 0.85344)
						(xy 0.09144 0.87376) (xy 0.0635 0.889) (xy 0.03175 0.89916)
					)
					(width 0)
					(fill yes)
				)
			)
		)
	)
)
